# BASEBOARD_FAB2 (Tioga Pass) — schematic netlist excerpt (pin names and nets, part order shuffled) for the footprints in the layout excerpt that follows; sources: Cadence DE-HDL packaged netlist, KiCad conversion of Wiwynn_Tioga_Pass_MB.brd

C2L40  CAP_A  0.01UF 25V 10% X7R  pkg 0402V  page 173 : A = SATA6G_P0_TX_C_DN ; B = SATA6G_PCH_PCIE_UP_SATA_TXN<0>
C3P39  CAP  0.22UF 16V 10% X7R  pkg 0402  page 107 : A = P3E_CPU0_PE1_SS_TXP<7> ; B = P3E_CPU0_PE1_PCH_TXP<7>
C5U8  CAP_A  47UF 4V 20% X5R  pkg 0603V  page 217 : A = PVDDQ_ABC ; B = GND

(kicad_pcb
	(version 20260206)
	(generator "pcbnew")
	(generator_version "10.0")
	(general
		(thickness 1.6)
		(legacy_teardrops no)
	)
	(paper "A4")
	(title_block
		(title "Wiwynn_Tioga_Pass_MB.brd")
		(comment 1 "Tioga Pass / footprints 3910-3912 of 4770")
	)
	(layers
		(0 "F.Cu" signal "TOP")
		(4 "In1.Cu" signal "L2GND")
		(6 "In2.Cu" signal "L3")
		(8 "In3.Cu" signal "L4GND")
		(10 "In4.Cu" signal "L5")
		(12 "In5.Cu" signal "L6GND")
		(14 "In6.Cu" signal "L7VCC")
		(16 "In7.Cu" signal "L8VCC")
		(18 "In8.Cu" signal "L9GND")
		(20 "In9.Cu" signal "L10")
		(22 "In10.Cu" signal "L11GND")
		(24 "In11.Cu" signal "L12")
		(26 "In12.Cu" signal "L13GND")
		(2 "B.Cu" signal "BOTTOM")
		(9 "F.Adhes" user "F.Adhesive")
		(11 "B.Adhes" user "B.Adhesive")
		(13 "F.Paste" user "Package Geometry/Pastemask Top")
		(15 "B.Paste" user "Package Geometry/Pastemask Bottom")
		(5 "F.SilkS" user "Ref Des/Silkscreen Top")
		(7 "B.SilkS" user "Ref Des/Silkscreen Bottom")
		(1 "F.Mask" user "Board Geometry/Soldermask Top")
		(3 "B.Mask" user "Board Geometry/Soldermask Bottom")
		(17 "Dwgs.User" user "User.Drawings")
		(19 "Cmts.User" user "User.Comments")
		(21 "Eco1.User" user "User.Eco1")
		(23 "Eco2.User" user "User.Eco2")
		(25 "Edge.Cuts" user "Board Geometry/Outline")
		(27 "Margin" user)
		(31 "F.CrtYd" user "Package Geometry/Place Bound Top")
		(29 "B.CrtYd" user "Package Geometry/Place Bound Bottom")
		(35 "F.Fab" user "Ref Des/Assembly Top")
		(33 "B.Fab" user "Ref Des/Assembly Bottom")
	)
	(footprint ""
		(layer "B.Cu")
		(at 248.8565 -8.1534 -90)
		(property "Reference" "C5U8"
			(at -1.848866 0.752348 270)
			(unlocked yes)
			(layer "B.SilkS")
			(effects
				(font
					(size 1.27 0.9652)
					(thickness 0.1524)
				)
				(justify mirror)
			)
		)
		(property "Value" ""
			(at 0 0 90)
			(layer "B.Fab")
			(effects
				(font
					(size 1.27 1.27)
				)
				(justify mirror)
			)
		)
		(duplicate_pad_numbers_are_jumpers no)
		(fp_rect
			(start 0.500126 1.598422)
			(end -0.500126 -0.201422)
			(stroke
				(width 0)
				(type default)
			)
			(fill no)
			(layer "B.CrtYd")
		)
		(fp_line
			(start -0.500126 1.598422)
			(end 0.500126 1.598422)
			(stroke
				(width 0.1)
				(type default)
			)
			(layer "B.Fab")
		)
		(fp_line
			(start 0.500126 1.598422)
			(end 0.500126 -0.201422)
			(stroke
				(width 0.1)
				(type default)
			)
			(layer "B.Fab")
		)
		(fp_line
			(start -0.500126 -0.201422)
			(end -0.500126 1.598422)
			(stroke
				(width 0.1)
				(type default)
			)
			(layer "B.Fab")
		)
		(fp_line
			(start 0.500126 -0.201422)
			(end -0.500126 -0.201422)
			(stroke
				(width 0.1)
				(type default)
			)
			(layer "B.Fab")
		)
		(pad "1" smd rect
			(at 0 0 180)
			(size 0.889 0.9906)
			(layers "B.Cu" "B.Mask" "B.Paste")
			(net "PVDDQ_ABC")
		)
		(pad "2" smd rect
			(at 0 1.397 180)
			(size 0.889 0.9906)
			(layers "B.Cu" "B.Mask" "B.Paste")
			(net "GND")
		)
		(zone
			(layer "B.Cu")
			(hatch none 0.5)
			(connect_pads
				(clearance 0)
			)
			(min_thickness 0.25)
			(keepout
				(tracks allowed)
				(vias not_allowed)
				(pads allowed)
				(copperpour not_allowed)
				(footprints allowed)
			)
			(placement
				(enabled no)
				(sheetname "")
			)
			(fill
				(thermal_gap 0.5)
				(thermal_bridge_width 0.5)
				(island_removal_mode 0)
			)
			(polygon
				(pts
					(xy 247.904 -7.6581) (xy 248.412 -7.6581) (xy 248.412 -8.6487) (xy 247.904 -8.6487)
				)
			)
		)
		(zone
			(layer "B.Cu")
			(hatch none 0.5)
			(connect_pads
				(clearance 0)
			)
			(min_thickness 0.25)
			(keepout
				(tracks not_allowed)
				(vias allowed)
				(pads allowed)
				(copperpour not_allowed)
				(footprints allowed)
			)
			(placement
				(enabled no)
				(sheetname "")
			)
			(fill
				(thermal_gap 0.5)
				(thermal_bridge_width 0.5)
				(island_removal_mode 0)
			)
			(polygon
				(pts
					(xy 247.904 -7.6581) (xy 248.412 -7.6581) (xy 248.412 -8.6487) (xy 247.904 -8.6487)
				)
			)
		)
	)
	(footprint ""
		(layer "B.Cu")
		(at 359.84688 -77.923136 180)
		(property "Reference" "C3P39"
			(at 0 0 0)
			(layer "B.SilkS")
			(hide yes)
			(effects
				(font
					(size 1.27 1.27)
				)
				(justify mirror)
			)
		)
		(property "Value" ""
			(at 0 0 0)
			(layer "B.Fab")
			(effects
				(font
					(size 1.27 1.27)
				)
				(justify mirror)
			)
		)
		(duplicate_pad_numbers_are_jumpers no)
		(fp_poly
			(pts
				(xy -0.3048 -0.1016) (xy -0.3048 0.9906) (xy 0.3048 0.9906) (xy 0.3048 -0.1016)
			)
			(stroke
				(width 0)
				(type default)
			)
			(fill no)
			(layer "B.CrtYd")
		)
		(fp_line
			(start 0.3048 0.9906)
			(end -0.3048 0.9906)
			(stroke
				(width 0.1)
				(type default)
			)
			(layer "B.Fab")
		)
		(fp_line
			(start 0.3048 -0.1016)
			(end 0.3048 0.9906)
			(stroke
				(width 0.1)
				(type default)
			)
			(layer "B.Fab")
		)
		(fp_line
			(start -0.3048 0.9906)
			(end -0.3048 -0.1016)
			(stroke
				(width 0.1)
				(type default)
			)
			(layer "B.Fab")
		)
		(fp_line
			(start -0.3048 -0.1016)
			(end 0.3048 -0.1016)
			(stroke
				(width 0.1)
				(type default)
			)
			(layer "B.Fab")
		)
		(pad "1" smd rect
			(at 0 0)
			(size 0.508 0.508)
			(layers "B.Cu" "B.Mask" "B.Paste")
			(net "P3E_CPU0_PE1_SS_TXP<7>")
		)
		(pad "2" smd rect
			(at 0 0.889)
			(size 0.508 0.508)
			(layers "B.Cu" "B.Mask" "B.Paste")
			(net "P3E_CPU0_PE1_PCH_TXP<7>")
		)
		(zone
			(layer "B.Cu")
			(hatch none 0.5)
			(connect_pads
				(clearance 0)
			)
			(min_thickness 0.25)
			(keepout
				(tracks not_allowed)
				(vias allowed)
				(pads allowed)
				(copperpour not_allowed)
				(footprints allowed)
			)
			(placement
				(enabled no)
				(sheetname "")
			)
			(fill
				(thermal_gap 0.5)
				(thermal_bridge_width 0.5)
				(island_removal_mode 0)
			)
			(polygon
				(pts
					(xy 359.59288 -78.558136) (xy 360.10088 -78.558136) (xy 360.10088 -78.177136) (xy 359.59288 -78.177136)
				)
			)
		)
		(zone
			(layer "B.Cu")
			(hatch none 0.5)
			(connect_pads
				(clearance 0)
			)
			(min_thickness 0.25)
			(keepout
				(tracks allowed)
				(vias not_allowed)
				(pads allowed)
				(copperpour not_allowed)
				(footprints allowed)
			)
			(placement
				(enabled no)
				(sheetname "")
			)
			(fill
				(thermal_gap 0.5)
				(thermal_bridge_width 0.5)
				(island_removal_mode 0)
			)
			(polygon
				(pts
					(xy 359.59288 -78.177136) (xy 360.10088 -78.177136) (xy 360.10088 -78.558136) (xy 359.59288 -78.558136)
				)
			)
		)
	)
	(footprint ""
		(layer "B.Cu")
		(at 426.72 -142.0876)
		(property "Reference" "C2L40"
			(at 0 0 0)
			(layer "B.SilkS")
			(hide yes)
			(effects
				(font
					(size 1.27 1.27)
				)
				(justify mirror)
			)
		)
		(property "Value" ""
			(at 0 0 0)
			(layer "B.Fab")
			(effects
				(font
					(size 1.27 1.27)
				)
				(justify mirror)
			)
		)
		(duplicate_pad_numbers_are_jumpers no)
		(fp_poly
			(pts
				(xy -0.3048 -0.1016) (xy -0.3048 0.9906) (xy 0.3048 0.9906) (xy 0.3048 -0.1016)
			)
			(stroke
				(width 0)
				(type default)
			)
			(fill no)
			(layer "B.CrtYd")
		)
		(fp_line
			(start -0.3048 -0.1016)
			(end 0.3048 -0.1016)
			(stroke
				(width 0.1)
				(type default)
			)
			(layer "B.Fab")
		)
		(fp_line
			(start -0.3048 0.9906)
			(end -0.3048 -0.1016)
			(stroke
				(width 0.1)
				(type default)
			)
			(layer "B.Fab")
		)
		(fp_line
			(start 0.3048 -0.1016)
			(end 0.3048 0.9906)
			(stroke
				(width 0.1)
				(type default)
			)
			(layer "B.Fab")
		)
		(fp_line
			(start 0.3048 0.9906)
			(end -0.3048 0.9906)
			(stroke
				(width 0.1)
				(type default)
			)
			(layer "B.Fab")
		)
		(pad "1" smd rect
			(at 0 0 180)
			(size 0.508 0.508)
			(layers "B.Cu" "B.Mask" "B.Paste")
			(net "SATA6G_P0_TX_C_DN")
		)
		(pad "2" smd rect
			(at 0 0.889 180)
			(size 0.508 0.508)
			(layers "B.Cu" "B.Mask" "B.Paste")
			(net "SATA6G_PCH_PCIE_UP_SATA_TXN<0>")
		)
		(zone
			(layer "B.Cu")
			(hatch none 0.5)
			(connect_pads
				(clearance 0)
			)
			(min_thickness 0.25)
			(keepout
				(tracks allowed)
				(vias not_allowed)
				(pads allowed)
				(copperpour not_allowed)
				(footprints allowed)
			)
			(placement
				(enabled no)
				(sheetname "")
			)
			(fill
				(thermal_gap 0.5)
				(thermal_bridge_width 0.5)
				(island_removal_mode 0)
			)
			(polygon
				(pts
					(xy 426.974 -141.8336) (xy 426.466 -141.8336) (xy 426.466 -141.4526) (xy 426.974 -141.4526)
				)
			)
		)
		(zone
			(layer "B.Cu")
			(hatch none 0.5)
			(connect_pads
				(clearance 0)
			)
			(min_thickness 0.25)
			(keepout
				(tracks not_allowed)
				(vias allowed)
				(pads allowed)
				(copperpour not_allowed)
				(footprints allowed)
			)
			(placement
				(enabled no)
				(sheetname "")
			)
			(fill
				(thermal_gap 0.5)
				(thermal_bridge_width 0.5)
				(island_removal_mode 0)
			)
			(polygon
				(pts
					(xy 426.974 -141.4526) (xy 426.466 -141.4526) (xy 426.466 -141.8336) (xy 426.974 -141.8336)
				)
			)
		)
	)
)
